# T6G (Grand Teton) — schematic netlist excerpt (pin names and nets, part order shuffled) for the footprints in the layout excerpt that follows; sources: Cadence DE-HDL packaged netlist, KiCad conversion of 04192023_DAF0TMB3IC0_F0TG_MB_C_brd_V02_OCP.brd

PR107  Q_RES  2.2 1% CHIP  pkg 0402LF  page 206 : A = PVDDCR_CPU1_P0_PVCC ; B = PVDDIO_P0_VCC4
C25  Q_CAP  0.1UF 25V 10% X7R  pkg 0402  page 161 : A = P3V3_AUX ; B = GND
PC305_4  Q_CAP  22UF 4V 20% X6S  pkg C0805  page 212 : A = PVDDCR_CPU0_P1 ; B = GND

(kicad_pcb
	(version 20260206)
	(generator "pcbnew")
	(generator_version "10.0")
	(general
		(thickness 1.6)
		(legacy_teardrops no)
	)
	(paper "A4")
	(title_block
		(title "04192023_DAF0TMB3IC0_F0TG_MB_C_brd_V02_OCP.brd")
		(comment 1 "Grand Teton / footprints 8147-8149 of 8354")
	)
	(layers
		(0 "F.Cu" signal "TOP")
		(4 "In1.Cu" signal "GND")
		(6 "In2.Cu" signal "IN1")
		(8 "In3.Cu" signal "GND1")
		(10 "In4.Cu" signal "IN2")
		(12 "In5.Cu" signal "GND2")
		(14 "In6.Cu" signal "IN3")
		(16 "In7.Cu" signal "GND3")
		(18 "In8.Cu" signal "VCC")
		(20 "In9.Cu" signal "VCC1")
		(22 "In10.Cu" signal "GND4")
		(24 "In11.Cu" signal "IN4")
		(26 "In12.Cu" signal "GND5")
		(28 "In13.Cu" signal "IN5")
		(30 "In14.Cu" signal "GND6")
		(32 "In15.Cu" signal "IN6")
		(34 "In16.Cu" signal "GND7")
		(2 "B.Cu" signal "BOTTOM")
		(9 "F.Adhes" user "F.Adhesive")
		(11 "B.Adhes" user "B.Adhesive")
		(13 "F.Paste" user "Package Geometry/Pastemask Top")
		(15 "B.Paste" user "Package Geometry/Pastemask Bottom")
		(5 "F.SilkS" user "Ref Des/Silkscreen Top")
		(7 "B.SilkS" user "Ref Des/Silkscreen Bottom")
		(1 "F.Mask" user "Board Geometry/Soldermask Top")
		(3 "B.Mask" user "Board Geometry/Soldermask Bottom")
		(17 "Dwgs.User" user "User.Drawings")
		(19 "Cmts.User" user "User.Comments")
		(21 "Eco1.User" user "User.Eco1")
		(23 "Eco2.User" user "User.Eco2")
		(25 "Edge.Cuts" user "Board Geometry/Outline")
		(27 "Margin" user)
		(31 "F.CrtYd" user "Package Geometry/Place Bound Top")
		(29 "B.CrtYd" user "Package Geometry/Place Bound Bottom")
		(35 "F.Fab" user "Ref Des/Assembly Top")
		(33 "B.Fab" user "Ref Des/Assembly Bottom")
	)
	(footprint ""
		(layer "B.Cu")
		(at 111.214154 -190.870332 90)
		(property "Reference" "PC305_4"
			(at 0 0 90)
			(layer "B.SilkS")
			(hide yes)
			(effects
				(font
					(size 1.27 1.27)
				)
				(justify mirror)
			)
		)
		(property "Value" ""
			(at 0 0 90)
			(layer "B.Fab")
			(effects
				(font
					(size 1.27 1.27)
				)
				(justify mirror)
			)
		)
		(duplicate_pad_numbers_are_jumpers no)
		(fp_line
			(start 1.524 -0.762)
			(end -1.524 -0.762)
			(stroke
				(width 0.1524)
				(type default)
			)
			(layer "B.SilkS")
		)
		(fp_line
			(start -1.524 -0.762)
			(end -1.524 0.762)
			(stroke
				(width 0.1524)
				(type default)
			)
			(layer "B.SilkS")
		)
		(fp_line
			(start 1.524 0.762)
			(end 1.524 -0.762)
			(stroke
				(width 0.1524)
				(type default)
			)
			(layer "B.SilkS")
		)
		(fp_line
			(start -1.524 0.762)
			(end 1.524 0.762)
			(stroke
				(width 0.1524)
				(type default)
			)
			(layer "B.SilkS")
		)
		(fp_line
			(start 1.1049 -0.724916)
			(end 1.1049 0.724916)
			(stroke
				(width 0.1)
				(type default)
			)
			(layer "B.Fab")
		)
		(fp_line
			(start -1.1049 -0.724916)
			(end 1.1049 -0.724916)
			(stroke
				(width 0.1)
				(type default)
			)
			(layer "B.Fab")
		)
		(fp_line
			(start 1.1049 0.724916)
			(end -1.1049 0.724916)
			(stroke
				(width 0.1)
				(type default)
			)
			(layer "B.Fab")
		)
		(fp_line
			(start -1.1049 0.724916)
			(end -1.1049 -0.724916)
			(stroke
				(width 0.1)
				(type default)
			)
			(layer "B.Fab")
		)
		(pad "1" smd rect
			(at 0.889 0 90)
			(size 1.016 1.27)
			(layers "B.Cu" "B.Mask" "B.Paste")
			(net "PVDDCR_CPU0_P1")
		)
		(pad "2" smd rect
			(at -0.889 0 90)
			(size 1.016 1.27)
			(layers "B.Cu" "B.Mask" "B.Paste")
			(net "GND")
		)
	)
	(footprint ""
		(layer "B.Cu")
		(at 240.919 -236.855 90)
		(property "Reference" "C25"
			(at 0 0 90)
			(layer "B.SilkS")
			(hide yes)
			(effects
				(font
					(size 1.27 1.27)
				)
				(justify mirror)
			)
		)
		(property "Value" ""
			(at 0 0 90)
			(layer "B.Fab")
			(effects
				(font
					(size 1.27 1.27)
				)
				(justify mirror)
			)
		)
		(duplicate_pad_numbers_are_jumpers no)
		(fp_line
			(start 0.7874 -0.4064)
			(end -0.7874 -0.4064)
			(stroke
				(width 0.1524)
				(type default)
			)
			(layer "B.SilkS")
		)
		(fp_line
			(start -0.7874 -0.4064)
			(end -0.7874 0.4064)
			(stroke
				(width 0.1524)
				(type default)
			)
			(layer "B.SilkS")
		)
		(fp_line
			(start 0.7874 0.4064)
			(end 0.7874 -0.4064)
			(stroke
				(width 0.1524)
				(type default)
			)
			(layer "B.SilkS")
		)
		(fp_line
			(start -0.7874 0.4064)
			(end 0.7874 0.4064)
			(stroke
				(width 0.1524)
				(type default)
			)
			(layer "B.SilkS")
		)
		(fp_line
			(start 0.67945 -0.305054)
			(end 0.12065 -0.305054)
			(stroke
				(width 0.1)
				(type default)
			)
			(layer "B.Fab")
		)
		(fp_line
			(start 0.12065 -0.305054)
			(end 0.12065 -0.2794)
			(stroke
				(width 0.1)
				(type default)
			)
			(layer "B.Fab")
		)
		(fp_line
			(start -0.12065 -0.3048)
			(end -0.67945 -0.3048)
			(stroke
				(width 0.1)
				(type default)
			)
			(layer "B.Fab")
		)
		(fp_line
			(start -0.67945 -0.3048)
			(end -0.67945 0.3048)
			(stroke
				(width 0.1)
				(type default)
			)
			(layer "B.Fab")
		)
		(fp_line
			(start 0.12065 -0.2794)
			(end -0.12065 -0.2794)
			(stroke
				(width 0.1)
				(type default)
			)
			(layer "B.Fab")
		)
		(fp_line
			(start -0.12065 -0.2794)
			(end -0.12065 -0.3048)
			(stroke
				(width 0.1)
				(type default)
			)
			(layer "B.Fab")
		)
		(fp_line
			(start 0.12065 0.2794)
			(end 0.12065 0.3048)
			(stroke
				(width 0.1)
				(type default)
			)
			(layer "B.Fab")
		)
		(fp_line
			(start -0.120396 0.2794)
			(end 0.12065 0.2794)
			(stroke
				(width 0.1)
				(type default)
			)
			(layer "B.Fab")
		)
		(fp_line
			(start 0.67945 0.3048)
			(end 0.67945 -0.305054)
			(stroke
				(width 0.1)
				(type default)
			)
			(layer "B.Fab")
		)
		(fp_line
			(start 0.12065 0.3048)
			(end 0.67945 0.3048)
			(stroke
				(width 0.1)
				(type default)
			)
			(layer "B.Fab")
		)
		(fp_line
			(start -0.120396 0.3048)
			(end -0.120396 0.2794)
			(stroke
				(width 0.1)
				(type default)
			)
			(layer "B.Fab")
		)
		(fp_line
			(start -0.67945 0.3048)
			(end -0.120396 0.3048)
			(stroke
				(width 0.1)
				(type default)
			)
			(layer "B.Fab")
		)
		(pad "1" smd circle
			(at 0.40005 0 270)
			(size 0 0)
			(layers "B.Cu" "B.Mask" "B.Paste")
			(net "P3V3_AUX")
		)
		(pad "2" smd circle
			(at -0.40005 0 270)
			(size 0 0)
			(layers "B.Cu" "B.Mask" "B.Paste")
			(net "GND")
		)
	)
	(footprint ""
		(layer "B.Cu")
		(at 273.111214 -347.77553 -90)
		(property "Reference" "PR107"
			(at 0 0 90)
			(layer "B.SilkS")
			(hide yes)
			(effects
				(font
					(size 1.27 1.27)
				)
				(justify mirror)
			)
		)
		(property "Value" ""
			(at 0 0 90)
			(layer "B.Fab")
			(effects
				(font
					(size 1.27 1.27)
				)
				(justify mirror)
			)
		)
		(duplicate_pad_numbers_are_jumpers no)
		(fp_line
			(start -0.7874 0.4064)
			(end 0.7874 0.4064)
			(stroke
				(width 0.1524)
				(type default)
			)
			(layer "B.SilkS")
		)
		(fp_line
			(start 0.7874 0.4064)
			(end 0.7874 -0.4064)
			(stroke
				(width 0.1524)
				(type default)
			)
			(layer "B.SilkS")
		)
		(fp_line
			(start -0.7874 -0.4064)
			(end -0.7874 0.4064)
			(stroke
				(width 0.1524)
				(type default)
			)
			(layer "B.SilkS")
		)
		(fp_line
			(start 0.7874 -0.4064)
			(end -0.7874 -0.4064)
			(stroke
				(width 0.1524)
				(type default)
			)
			(layer "B.SilkS")
		)
		(fp_line
			(start -0.67945 0.3048)
			(end -0.120396 0.3048)
			(stroke
				(width 0.1)
				(type default)
			)
			(layer "B.Fab")
		)
		(fp_line
			(start -0.120396 0.3048)
			(end -0.120396 0.2794)
			(stroke
				(width 0.1)
				(type default)
			)
			(layer "B.Fab")
		)
		(fp_line
			(start 0.12065 0.3048)
			(end 0.67945 0.3048)
			(stroke
				(width 0.1)
				(type default)
			)
			(layer "B.Fab")
		)
		(fp_line
			(start 0.67945 0.3048)
			(end 0.67945 -0.305054)
			(stroke
				(width 0.1)
				(type default)
			)
			(layer "B.Fab")
		)
		(fp_line
			(start -0.120396 0.2794)
			(end 0.12065 0.2794)
			(stroke
				(width 0.1)
				(type default)
			)
			(layer "B.Fab")
		)
		(fp_line
			(start 0.12065 0.2794)
			(end 0.12065 0.3048)
			(stroke
				(width 0.1)
				(type default)
			)
			(layer "B.Fab")
		)
		(fp_line
			(start -0.12065 -0.2794)
			(end -0.12065 -0.3048)
			(stroke
				(width 0.1)
				(type default)
			)
			(layer "B.Fab")
		)
		(fp_line
			(start 0.12065 -0.2794)
			(end -0.12065 -0.2794)
			(stroke
				(width 0.1)
				(type default)
			)
			(layer "B.Fab")
		)
		(fp_line
			(start -0.67945 -0.3048)
			(end -0.67945 0.3048)
			(stroke
				(width 0.1)
				(type default)
			)
			(layer "B.Fab")
		)
		(fp_line
			(start -0.12065 -0.3048)
			(end -0.67945 -0.3048)
			(stroke
				(width 0.1)
				(type default)
			)
			(layer "B.Fab")
		)
		(fp_line
			(start 0.12065 -0.305054)
			(end 0.12065 -0.2794)
			(stroke
				(width 0.1)
				(type default)
			)
			(layer "B.Fab")
		)
		(fp_line
			(start 0.67945 -0.305054)
			(end 0.12065 -0.305054)
			(stroke
				(width 0.1)
				(type default)
			)
			(layer "B.Fab")
		)
		(pad "1" smd circle
			(at 0.40005 0 90)
			(size 0 0)
			(layers "B.Cu" "B.Mask" "B.Paste")
			(net "PVDDCR_CPU1_P0_PVCC")
		)
		(pad "2" smd circle
			(at -0.40005 0 90)
			(size 0 0)
			(layers "B.Cu" "B.Mask" "B.Paste")
			(net "PVDDIO_P0_VCC4")
		)
	)
)
